(kicad_pcb
	(version 20260206)
	(generator "pcbnew")
	(generator_version "10.0")
	(general
		(thickness 1.6)
		(legacy_teardrops no)
	)
	(paper "A4")
	(title_block
		(title "01162023_DA0F0TEBIF0_F0T_Expander_BD_F_brd_V02_OCP.brd")
		(comment 1 "Grand Teton / footprints 8772-8780 of 9728")
	)
	(layers
		(0 "F.Cu" signal "TOP")
		(4 "In1.Cu" signal "GND")
		(6 "In2.Cu" signal "VCC")
		(8 "In3.Cu" signal "VCC1")
		(10 "In4.Cu" signal "GND1")
		(12 "In5.Cu" signal "IN1")
		(14 "In6.Cu" signal "GND2")
		(16 "In7.Cu" signal "IN2")
		(18 "In8.Cu" signal "GND3")
		(20 "In9.Cu" signal "IN3")
		(22 "In10.Cu" signal "GND4")
		(24 "In11.Cu" signal "IN4")
		(26 "In12.Cu" signal "GND5")
		(28 "In13.Cu" signal "IN5")
		(30 "In14.Cu" signal "GND6")
		(32 "In15.Cu" signal "IN6")
		(34 "In16.Cu" signal "GND7")
		(2 "B.Cu" signal "BOTTOM")
		(9 "F.Adhes" user "F.Adhesive")
		(11 "B.Adhes" user "B.Adhesive")
		(13 "F.Paste" user "Package Geometry/Pastemask Top")
		(15 "B.Paste" user "Package Geometry/Pastemask Bottom")
		(5 "F.SilkS" user "Ref Des/Silkscreen Top")
		(7 "B.SilkS" user "Ref Des/Silkscreen Bottom")
		(1 "F.Mask" user "Board Geometry/Soldermask Top")
		(3 "B.Mask" user "Board Geometry/Soldermask Bottom")
		(17 "Dwgs.User" user "User.Drawings")
		(19 "Cmts.User" user "User.Comments")
		(21 "Eco1.User" user "User.Eco1")
		(23 "Eco2.User" user "User.Eco2")
		(25 "Edge.Cuts" user "Board Geometry/Outline")
		(27 "Margin" user)
		(31 "F.CrtYd" user "Package Geometry/Place Bound Top")
		(29 "B.CrtYd" user "Package Geometry/Place Bound Bottom")
		(35 "F.Fab" user "Ref Des/Assembly Top")
		(33 "B.Fab" user "Ref Des/Assembly Bottom")
	)
	(footprint ""
		(layer "B.Cu")
		(at 339.725 -207.772 90)
		(property "Reference" "R4129"
			(at 0 0 90)
			(layer "B.SilkS")
			(hide yes)
			(effects
				(font
					(size 1.27 1.27)
				)
				(justify mirror)
			)
		)
		(property "Value" ""
			(at 0 0 90)
			(layer "B.Fab")
			(effects
				(font
					(size 1.27 1.27)
				)
				(justify mirror)
			)
		)
		(duplicate_pad_numbers_are_jumpers no)
		(fp_line
			(start 0.7874 -0.4064)
			(end -0.7874 -0.4064)
			(stroke
				(width 0.1524)
				(type default)
			)
			(layer "B.SilkS")
		)
		(fp_line
			(start -0.7874 -0.4064)
			(end -0.7874 0.4064)
			(stroke
				(width 0.1524)
				(type default)
			)
			(layer "B.SilkS")
		)
		(fp_line
			(start 0.7874 0.4064)
			(end 0.7874 -0.4064)
			(stroke
				(width 0.1524)
				(type default)
			)
			(layer "B.SilkS")
		)
		(fp_line
			(start -0.7874 0.4064)
			(end 0.7874 0.4064)
			(stroke
				(width 0.1524)
				(type default)
			)
			(layer "B.SilkS")
		)
		(fp_line
			(start 0.67945 -0.305054)
			(end 0.12065 -0.305054)
			(stroke
				(width 0.1)
				(type default)
			)
			(layer "B.Fab")
		)
		(fp_line
			(start 0.12065 -0.305054)
			(end 0.12065 -0.2794)
			(stroke
				(width 0.1)
				(type default)
			)
			(layer "B.Fab")
		)
		(fp_line
			(start -0.12065 -0.3048)
			(end -0.67945 -0.3048)
			(stroke
				(width 0.1)
				(type default)
			)
			(layer "B.Fab")
		)
		(fp_line
			(start -0.67945 -0.3048)
			(end -0.67945 0.3048)
			(stroke
				(width 0.1)
				(type default)
			)
			(layer "B.Fab")
		)
		(fp_line
			(start 0.12065 -0.2794)
			(end -0.12065 -0.2794)
			(stroke
				(width 0.1)
				(type default)
			)
			(layer "B.Fab")
		)
		(fp_line
			(start -0.12065 -0.2794)
			(end -0.12065 -0.3048)
			(stroke
				(width 0.1)
				(type default)
			)
			(layer "B.Fab")
		)
		(fp_line
			(start 0.12065 0.2794)
			(end 0.12065 0.3048)
			(stroke
				(width 0.1)
				(type default)
			)
			(layer "B.Fab")
		)
		(fp_line
			(start -0.120396 0.2794)
			(end 0.12065 0.2794)
			(stroke
				(width 0.1)
				(type default)
			)
			(layer "B.Fab")
		)
		(fp_line
			(start 0.67945 0.3048)
			(end 0.67945 -0.305054)
			(stroke
				(width 0.1)
				(type default)
			)
			(layer "B.Fab")
		)
		(fp_line
			(start 0.12065 0.3048)
			(end 0.67945 0.3048)
			(stroke
				(width 0.1)
				(type default)
			)
			(layer "B.Fab")
		)
		(fp_line
			(start -0.120396 0.3048)
			(end -0.120396 0.2794)
			(stroke
				(width 0.1)
				(type default)
			)
			(layer "B.Fab")
		)
		(fp_line
			(start -0.67945 0.3048)
			(end -0.120396 0.3048)
			(stroke
				(width 0.1)
				(type default)
			)
			(layer "B.Fab")
		)
		(pad "1" smd circle
			(at 0.40005 0 270)
			(size 0 0)
			(layers "B.Cu" "B.Mask" "B.Paste")
			(net "RST_SSD11_PERST_N")
		)
		(pad "2" smd circle
			(at -0.40005 0 270)
			(size 0 0)
			(layers "B.Cu" "B.Mask" "B.Paste")
			(net "RST_SSD11_PERST_R_N")
		)
	)
	(footprint ""
		(layer "B.Cu")
		(at 222.482664 -207.02016 -90)
		(property "Reference" "R5528"
			(at 0 0 90)
			(layer "B.SilkS")
			(hide yes)
			(effects
				(font
					(size 1.27 1.27)
				)
				(justify mirror)
			)
		)
		(property "Value" ""
			(at 0 0 90)
			(layer "B.Fab")
			(effects
				(font
					(size 1.27 1.27)
				)
				(justify mirror)
			)
		)
		(duplicate_pad_numbers_are_jumpers no)
		(fp_line
			(start -0.7874 0.4064)
			(end 0.7874 0.4064)
			(stroke
				(width 0.1524)
				(type default)
			)
			(layer "B.SilkS")
		)
		(fp_line
			(start 0.7874 0.4064)
			(end 0.7874 -0.4064)
			(stroke
				(width 0.1524)
				(type default)
			)
			(layer "B.SilkS")
		)
		(fp_line
			(start -0.7874 -0.4064)
			(end -0.7874 0.4064)
			(stroke
				(width 0.1524)
				(type default)
			)
			(layer "B.SilkS")
		)
		(fp_line
			(start 0.7874 -0.4064)
			(end -0.7874 -0.4064)
			(stroke
				(width 0.1524)
				(type default)
			)
			(layer "B.SilkS")
		)
		(fp_line
			(start -0.67945 0.3048)
			(end -0.120396 0.3048)
			(stroke
				(width 0.1)
				(type default)
			)
			(layer "B.Fab")
		)
		(fp_line
			(start -0.120396 0.3048)
			(end -0.120396 0.2794)
			(stroke
				(width 0.1)
				(type default)
			)
			(layer "B.Fab")
		)
		(fp_line
			(start 0.12065 0.3048)
			(end 0.67945 0.3048)
			(stroke
				(width 0.1)
				(type default)
			)
			(layer "B.Fab")
		)
		(fp_line
			(start 0.67945 0.3048)
			(end 0.67945 -0.305054)
			(stroke
				(width 0.1)
				(type default)
			)
			(layer "B.Fab")
		)
		(fp_line
			(start -0.120396 0.2794)
			(end 0.12065 0.2794)
			(stroke
				(width 0.1)
				(type default)
			)
			(layer "B.Fab")
		)
		(fp_line
			(start 0.12065 0.2794)
			(end 0.12065 0.3048)
			(stroke
				(width 0.1)
				(type default)
			)
			(layer "B.Fab")
		)
		(fp_line
			(start -0.12065 -0.2794)
			(end -0.12065 -0.3048)
			(stroke
				(width 0.1)
				(type default)
			)
			(layer "B.Fab")
		)
		(fp_line
			(start 0.12065 -0.2794)
			(end -0.12065 -0.2794)
			(stroke
				(width 0.1)
				(type default)
			)
			(layer "B.Fab")
		)
		(fp_line
			(start -0.67945 -0.3048)
			(end -0.67945 0.3048)
			(stroke
				(width 0.1)
				(type default)
			)
			(layer "B.Fab")
		)
		(fp_line
			(start -0.12065 -0.3048)
			(end -0.67945 -0.3048)
			(stroke
				(width 0.1)
				(type default)
			)
			(layer "B.Fab")
		)
		(fp_line
			(start 0.12065 -0.305054)
			(end 0.12065 -0.2794)
			(stroke
				(width 0.1)
				(type default)
			)
			(layer "B.Fab")
		)
		(fp_line
			(start 0.67945 -0.305054)
			(end 0.12065 -0.305054)
			(stroke
				(width 0.1)
				(type default)
			)
			(layer "B.Fab")
		)
		(pad "1" smd circle
			(at 0.40005 0 90)
			(size 0 0)
			(layers "B.Cu" "B.Mask" "B.Paste")
			(net "GND")
		)
		(pad "2" smd circle
			(at -0.40005 0 90)
			(size 0 0)
			(layers "B.Cu" "B.Mask" "B.Paste")
			(net "SGPIO_BIC_DOUT")
		)
	)
	(footprint ""
		(layer "B.Cu")
		(at 417.450016 -303.024794)
		(property "Reference" "C3513"
			(at 0 0 0)
			(layer "B.SilkS")
			(hide yes)
			(effects
				(font
					(size 1.27 1.27)
				)
				(justify mirror)
			)
		)
		(property "Value" ""
			(at 0 0 0)
			(layer "B.Fab")
			(effects
				(font
					(size 1.27 1.27)
				)
				(justify mirror)
			)
		)
		(duplicate_pad_numbers_are_jumpers no)
		(fp_line
			(start -0.299974 -0.150114)
			(end -0.299974 0.150114)
			(stroke
				(width 0.1)
				(type default)
			)
			(layer "B.Fab")
		)
		(fp_line
			(start -0.299974 0.150114)
			(end 0.299974 0.150114)
			(stroke
				(width 0.1)
				(type default)
			)
			(layer "B.Fab")
		)
		(fp_line
			(start 0.299974 -0.150114)
			(end -0.299974 -0.150114)
			(stroke
				(width 0.1)
				(type default)
			)
			(layer "B.Fab")
		)
		(fp_line
			(start 0.299974 0.150114)
			(end 0.299974 -0.150114)
			(stroke
				(width 0.1)
				(type default)
			)
			(layer "B.Fab")
		)
		(pad "1" smd rect
			(at 0.2667 0 180)
			(size 0.3048 0.381)
			(layers "B.Cu" "B.Mask" "B.Paste")
			(net "P1V8_PEX")
		)
		(pad "2" smd rect
			(at -0.2667 0 180)
			(size 0.3048 0.381)
			(layers "B.Cu" "B.Mask" "B.Paste")
			(net "GND")
		)
	)
	(footprint ""
		(layer "B.Cu")
		(at 207.110076 -221.694248 180)
		(property "Reference" "C4488"
			(at 0 0 0)
			(layer "B.SilkS")
			(hide yes)
			(effects
				(font
					(size 1.27 1.27)
				)
				(justify mirror)
			)
		)
		(property "Value" ""
			(at 0 0 0)
			(layer "B.Fab")
			(effects
				(font
					(size 1.27 1.27)
				)
				(justify mirror)
			)
		)
		(duplicate_pad_numbers_are_jumpers no)
		(fp_line
			(start 0.7874 0.4064)
			(end 0.7874 -0.4064)
			(stroke
				(width 0.1524)
				(type default)
			)
			(layer "B.SilkS")
		)
		(fp_line
			(start 0.7874 -0.4064)
			(end -0.7874 -0.4064)
			(stroke
				(width 0.1524)
				(type default)
			)
			(layer "B.SilkS")
		)
		(fp_line
			(start -0.7874 0.4064)
			(end 0.7874 0.4064)
			(stroke
				(width 0.1524)
				(type default)
			)
			(layer "B.SilkS")
		)
		(fp_line
			(start -0.7874 -0.4064)
			(end -0.7874 0.4064)
			(stroke
				(width 0.1524)
				(type default)
			)
			(layer "B.SilkS")
		)
		(fp_line
			(start 0.67945 0.3048)
			(end 0.67945 -0.305054)
			(stroke
				(width 0.1)
				(type default)
			)
			(layer "B.Fab")
		)
		(fp_line
			(start 0.67945 -0.305054)
			(end 0.12065 -0.305054)
			(stroke
				(width 0.1)
				(type default)
			)
			(layer "B.Fab")
		)
		(fp_line
			(start 0.12065 0.3048)
			(end 0.67945 0.3048)
			(stroke
				(width 0.1)
				(type default)
			)
			(layer "B.Fab")
		)
		(fp_line
			(start 0.12065 0.2794)
			(end 0.12065 0.3048)
			(stroke
				(width 0.1)
				(type default)
			)
			(layer "B.Fab")
		)
		(fp_line
			(start 0.12065 -0.2794)
			(end -0.12065 -0.2794)
			(stroke
				(width 0.1)
				(type default)
			)
			(layer "B.Fab")
		)
		(fp_line
			(start 0.12065 -0.305054)
			(end 0.12065 -0.2794)
			(stroke
				(width 0.1)
				(type default)
			)
			(layer "B.Fab")
		)
		(fp_line
			(start -0.120396 0.3048)
			(end -0.120396 0.2794)
			(stroke
				(width 0.1)
				(type default)
			)
			(layer "B.Fab")
		)
		(fp_line
			(start -0.120396 0.2794)
			(end 0.12065 0.2794)
			(stroke
				(width 0.1)
				(type default)
			)
			(layer "B.Fab")
		)
		(fp_line
			(start -0.12065 -0.2794)
			(end -0.12065 -0.3048)
			(stroke
				(width 0.1)
				(type default)
			)
			(layer "B.Fab")
		)
		(fp_line
			(start -0.12065 -0.3048)
			(end -0.67945 -0.3048)
			(stroke
				(width 0.1)
				(type default)
			)
			(layer "B.Fab")
		)
		(fp_line
			(start -0.67945 0.3048)
			(end -0.120396 0.3048)
			(stroke
				(width 0.1)
				(type default)
			)
			(layer "B.Fab")
		)
		(fp_line
			(start -0.67945 -0.3048)
			(end -0.67945 0.3048)
			(stroke
				(width 0.1)
				(type default)
			)
			(layer "B.Fab")
		)
		(pad "1" smd circle
			(at 0.40005 0)
			(size 0 0)
			(layers "B.Cu" "B.Mask" "B.Paste")
			(net "BOARD_TYPE_1_ADC_R")
		)
		(pad "2" smd circle
			(at -0.40005 0)
			(size 0 0)
			(layers "B.Cu" "B.Mask" "B.Paste")
			(net "GND")
		)
	)
	(footprint ""
		(layer "B.Cu")
		(at 193.641726 -95.989648 180)
		(property "Reference" "R164"
			(at 0 0 0)
			(layer "B.SilkS")
			(hide yes)
			(effects
				(font
					(size 1.27 1.27)
				)
				(justify mirror)
			)
		)
		(property "Value" ""
			(at 0 0 0)
			(layer "B.Fab")
			(effects
				(font
					(size 1.27 1.27)
				)
				(justify mirror)
			)
		)
		(duplicate_pad_numbers_are_jumpers no)
		(fp_line
			(start 0.7874 0.4064)
			(end 0.7874 -0.4064)
			(stroke
				(width 0.1524)
				(type default)
			)
			(layer "B.SilkS")
		)
		(fp_line
			(start 0.7874 -0.4064)
			(end -0.7874 -0.4064)
			(stroke
				(width 0.1524)
				(type default)
			)
			(layer "B.SilkS")
		)
		(fp_line
			(start -0.7874 0.4064)
			(end 0.7874 0.4064)
			(stroke
				(width 0.1524)
				(type default)
			)
			(layer "B.SilkS")
		)
		(fp_line
			(start -0.7874 -0.4064)
			(end -0.7874 0.4064)
			(stroke
				(width 0.1524)
				(type default)
			)
			(layer "B.SilkS")
		)
		(fp_line
			(start 0.67945 0.3048)
			(end 0.67945 -0.305054)
			(stroke
				(width 0.1)
				(type default)
			)
			(layer "B.Fab")
		)
		(fp_line
			(start 0.67945 -0.305054)
			(end 0.12065 -0.305054)
			(stroke
				(width 0.1)
				(type default)
			)
			(layer "B.Fab")
		)
		(fp_line
			(start 0.12065 0.3048)
			(end 0.67945 0.3048)
			(stroke
				(width 0.1)
				(type default)
			)
			(layer "B.Fab")
		)
		(fp_line
			(start 0.12065 0.2794)
			(end 0.12065 0.3048)
			(stroke
				(width 0.1)
				(type default)
			)
			(layer "B.Fab")
		)
		(fp_line
			(start 0.12065 -0.2794)
			(end -0.12065 -0.2794)
			(stroke
				(width 0.1)
				(type default)
			)
			(layer "B.Fab")
		)
		(fp_line
			(start 0.12065 -0.305054)
			(end 0.12065 -0.2794)
			(stroke
				(width 0.1)
				(type default)
			)
			(layer "B.Fab")
		)
		(fp_line
			(start -0.120396 0.3048)
			(end -0.120396 0.2794)
			(stroke
				(width 0.1)
				(type default)
			)
			(layer "B.Fab")
		)
		(fp_line
			(start -0.120396 0.2794)
			(end 0.12065 0.2794)
			(stroke
				(width 0.1)
				(type default)
			)
			(layer "B.Fab")
		)
		(fp_line
			(start -0.12065 -0.2794)
			(end -0.12065 -0.3048)
			(stroke
				(width 0.1)
				(type default)
			)
			(layer "B.Fab")
		)
		(fp_line
			(start -0.12065 -0.3048)
			(end -0.67945 -0.3048)
			(stroke
				(width 0.1)
				(type default)
			)
			(layer "B.Fab")
		)
		(fp_line
			(start -0.67945 0.3048)
			(end -0.120396 0.3048)
			(stroke
				(width 0.1)
				(type default)
			)
			(layer "B.Fab")
		)
		(fp_line
			(start -0.67945 -0.3048)
			(end -0.67945 0.3048)
			(stroke
				(width 0.1)
				(type default)
			)
			(layer "B.Fab")
		)
		(pad "1" smd circle
			(at 0.40005 0)
			(size 0 0)
			(layers "B.Cu" "B.Mask" "B.Paste")
			(net "NIC3_LD_N")
		)
		(pad "2" smd circle
			(at -0.40005 0)
			(size 0 0)
			(layers "B.Cu" "B.Mask" "B.Paste")
			(net "P3V3_NIC3")
		)
	)
	(footprint ""
		(layer "B.Cu")
		(at 290.89985 -299.699934 -90)
		(property "Reference" "C1701"
			(at 0 0 90)
			(layer "B.SilkS")
			(hide yes)
			(effects
				(font
					(size 1.27 1.27)
				)
				(justify mirror)
			)
		)
		(property "Value" ""
			(at 0 0 90)
			(layer "B.Fab")
			(effects
				(font
					(size 1.27 1.27)
				)
				(justify mirror)
			)
		)
		(duplicate_pad_numbers_are_jumpers no)
		(fp_line
			(start -0.299974 0.150114)
			(end 0.299974 0.150114)
			(stroke
				(width 0.1)
				(type default)
			)
			(layer "B.Fab")
		)
		(fp_line
			(start 0.299974 0.150114)
			(end 0.299974 -0.150114)
			(stroke
				(width 0.1)
				(type default)
			)
			(layer "B.Fab")
		)
		(fp_line
			(start -0.299974 -0.150114)
			(end -0.299974 0.150114)
			(stroke
				(width 0.1)
				(type default)
			)
			(layer "B.Fab")
		)
		(fp_line
			(start 0.299974 -0.150114)
			(end -0.299974 -0.150114)
			(stroke
				(width 0.1)
				(type default)
			)
			(layer "B.Fab")
		)
		(pad "1" smd rect
			(at 0.2667 0 90)
			(size 0.3048 0.381)
			(layers "B.Cu" "B.Mask" "B.Paste")
			(net "P0V8_SERDES_VDDA_PEX2")
		)
		(pad "2" smd rect
			(at -0.2667 0 90)
			(size 0.3048 0.381)
			(layers "B.Cu" "B.Mask" "B.Paste")
			(net "GND")
		)
	)
	(footprint ""
		(layer "B.Cu")
		(at 54.899814 -290.199826 90)
		(property "Reference" "C1199"
			(at 0 0 90)
			(layer "B.SilkS")
			(hide yes)
			(effects
				(font
					(size 1.27 1.27)
				)
				(justify mirror)
			)
		)
		(property "Value" ""
			(at 0 0 90)
			(layer "B.Fab")
			(effects
				(font
					(size 1.27 1.27)
				)
				(justify mirror)
			)
		)
		(duplicate_pad_numbers_are_jumpers no)
		(fp_line
			(start 0.299974 -0.150114)
			(end -0.299974 -0.150114)
			(stroke
				(width 0.1)
				(type default)
			)
			(layer "B.Fab")
		)
		(fp_line
			(start -0.299974 -0.150114)
			(end -0.299974 0.150114)
			(stroke
				(width 0.1)
				(type default)
			)
			(layer "B.Fab")
		)
		(fp_line
			(start 0.299974 0.150114)
			(end 0.299974 -0.150114)
			(stroke
				(width 0.1)
				(type default)
			)
			(layer "B.Fab")
		)
		(fp_line
			(start -0.299974 0.150114)
			(end 0.299974 0.150114)
			(stroke
				(width 0.1)
				(type default)
			)
			(layer "B.Fab")
		)
		(pad "1" smd rect
			(at 0.2667 0 270)
			(size 0.3048 0.381)
			(layers "B.Cu" "B.Mask" "B.Paste")
			(net "P0V8_SERDES_VDDA_PEX0")
		)
		(pad "2" smd rect
			(at -0.2667 0 270)
			(size 0.3048 0.381)
			(layers "B.Cu" "B.Mask" "B.Paste")
			(net "GND")
		)
	)
	(footprint ""
		(layer "B.Cu")
		(at 62.974982 -297.79976 -90)
		(property "Reference" "C1145"
			(at 0 0 90)
			(layer "B.SilkS")
			(hide yes)
			(effects
				(font
					(size 1.27 1.27)
				)
				(justify mirror)
			)
		)
		(property "Value" ""
			(at 0 0 90)
			(layer "B.Fab")
			(effects
				(font
					(size 1.27 1.27)
				)
				(justify mirror)
			)
		)
		(duplicate_pad_numbers_are_jumpers no)
		(fp_line
			(start -0.299974 0.150114)
			(end 0.299974 0.150114)
			(stroke
				(width 0.1)
				(type default)
			)
			(layer "B.Fab")
		)
		(fp_line
			(start 0.299974 0.150114)
			(end 0.299974 -0.150114)
			(stroke
				(width 0.1)
				(type default)
			)
			(layer "B.Fab")
		)
		(fp_line
			(start -0.299974 -0.150114)
			(end -0.299974 0.150114)
			(stroke
				(width 0.1)
				(type default)
			)
			(layer "B.Fab")
		)
		(fp_line
			(start 0.299974 -0.150114)
			(end -0.299974 -0.150114)
			(stroke
				(width 0.1)
				(type default)
			)
			(layer "B.Fab")
		)
		(pad "1" smd rect
			(at 0.2667 0 90)
			(size 0.3048 0.381)
			(layers "B.Cu" "B.Mask" "B.Paste")
			(net "P0V8_PEX0")
		)
		(pad "2" smd rect
			(at -0.2667 0 90)
			(size 0.3048 0.381)
			(layers "B.Cu" "B.Mask" "B.Paste")
			(net "GND")
		)
	)
	(footprint ""
		(layer "B.Cu")
		(at 417.924996 -305.608228 -90)
		(property "Reference" "C3518"
			(at 0 0 90)
			(layer "B.SilkS")
			(hide yes)
			(effects
				(font
					(size 1.27 1.27)
				)
				(justify mirror)
			)
		)
		(property "Value" ""
			(at 0 0 90)
			(layer "B.Fab")
			(effects
				(font
					(size 1.27 1.27)
				)
				(justify mirror)
			)
		)
		(duplicate_pad_numbers_are_jumpers no)
		(fp_line
			(start -0.299974 0.150114)
			(end 0.299974 0.150114)
			(stroke
				(width 0.1)
				(type default)
			)
			(layer "B.Fab")
		)
		(fp_line
			(start 0.299974 0.150114)
			(end 0.299974 -0.150114)
			(stroke
				(width 0.1)
				(type default)
			)
			(layer "B.Fab")
		)
		(fp_line
			(start -0.299974 -0.150114)
			(end -0.299974 0.150114)
			(stroke
				(width 0.1)
				(type default)
			)
			(layer "B.Fab")
		)
		(fp_line
			(start 0.299974 -0.150114)
			(end -0.299974 -0.150114)
			(stroke
				(width 0.1)
				(type default)
			)
			(layer "B.Fab")
		)
		(pad "1" smd rect
			(at 0.2667 0 90)
			(size 0.3048 0.381)
			(layers "B.Cu" "B.Mask" "B.Paste")
			(net "P1V8_VDDA_PEX3")
		)
		(pad "2" smd rect
			(at -0.2667 0 90)
			(size 0.3048 0.381)
			(layers "B.Cu" "B.Mask" "B.Paste")
			(net "GND")
		)
	)
)
